# BASEBOARD_FAB2 (Tioga Pass) — schematic netlist excerpt (pin names and nets, part order shuffled) for the footprints in the layout excerpt that follows; sources: Cadence DE-HDL packaged netlist, KiCad conversion of Wiwynn_Tioga_Pass_MB.brd

RF13  RES  1.0K 0.1% CHIP  pkg 0402  page 211 : A = VR_PVCCIO_CPU0_AIREF1 ; B = ISENSE_PVCCIO_CPU0_PH1_IMON
R2N26  RES  33.2 1% CHIP  pkg 0402  page 120 : A = FM_ADR_COMPLETE ; B = FM_ADR_COMPLETE_R1
C8L3  CAP  100UF 4V 20% X5R  pkg 0805  page 230 : A = PVTT_KLM ; B = GND

(kicad_pcb
	(version 20260206)
	(generator "pcbnew")
	(generator_version "10.0")
	(general
		(thickness 1.6)
		(legacy_teardrops no)
	)
	(paper "A4")
	(title_block
		(title "Wiwynn_Tioga_Pass_MB.brd")
		(comment 1 "Tioga Pass / footprints 2573-2575 of 4770")
	)
	(layers
		(0 "F.Cu" signal "TOP")
		(4 "In1.Cu" signal "L2GND")
		(6 "In2.Cu" signal "L3")
		(8 "In3.Cu" signal "L4GND")
		(10 "In4.Cu" signal "L5")
		(12 "In5.Cu" signal "L6GND")
		(14 "In6.Cu" signal "L7VCC")
		(16 "In7.Cu" signal "L8VCC")
		(18 "In8.Cu" signal "L9GND")
		(20 "In9.Cu" signal "L10")
		(22 "In10.Cu" signal "L11GND")
		(24 "In11.Cu" signal "L12")
		(26 "In12.Cu" signal "L13GND")
		(2 "B.Cu" signal "BOTTOM")
		(9 "F.Adhes" user "F.Adhesive")
		(11 "B.Adhes" user "B.Adhesive")
		(13 "F.Paste" user "Package Geometry/Pastemask Top")
		(15 "B.Paste" user "Package Geometry/Pastemask Bottom")
		(5 "F.SilkS" user "Ref Des/Silkscreen Top")
		(7 "B.SilkS" user "Ref Des/Silkscreen Bottom")
		(1 "F.Mask" user "Board Geometry/Soldermask Top")
		(3 "B.Mask" user "Board Geometry/Soldermask Bottom")
		(17 "Dwgs.User" user "User.Drawings")
		(19 "Cmts.User" user "User.Comments")
		(21 "Eco1.User" user "User.Eco1")
		(23 "Eco2.User" user "User.Eco2")
		(25 "Edge.Cuts" user "Board Geometry/Outline")
		(27 "Margin" user)
		(31 "F.CrtYd" user "Package Geometry/Place Bound Top")
		(29 "B.CrtYd" user "Package Geometry/Place Bound Bottom")
		(35 "F.Fab" user "Ref Des/Assembly Top")
		(33 "B.Fab" user "Ref Des/Assembly Bottom")
	)
	(footprint ""
		(layer "B.Cu")
		(at 344.461846 -90.97137 90)
		(property "Reference" "RF13"
			(at 0.8382 -0.67818 90)
			(unlocked yes)
			(layer "B.SilkS")
			(effects
				(font
					(size 0.4064 0.254)
					(thickness 0.1524)
				)
				(justify left mirror)
			)
		)
		(property "Value" ""
			(at 0 0 90)
			(layer "B.Fab")
			(effects
				(font
					(size 1.27 1.27)
				)
				(justify mirror)
			)
		)
		(duplicate_pad_numbers_are_jumpers no)
		(fp_poly
			(pts
				(xy 0.2794 -0.1016) (xy -0.2794 -0.1016) (xy -0.2794 0.9906) (xy 0.2794 0.9906)
			)
			(stroke
				(width 0)
				(type default)
			)
			(fill no)
			(layer "B.CrtYd")
		)
		(fp_line
			(start 0.2794 -0.1016)
			(end 0.2794 0.9906)
			(stroke
				(width 0.1)
				(type default)
			)
			(layer "B.Fab")
		)
		(fp_line
			(start -0.2794 -0.1016)
			(end 0.2794 -0.1016)
			(stroke
				(width 0.1)
				(type default)
			)
			(layer "B.Fab")
		)
		(fp_line
			(start 0.2794 0.9906)
			(end -0.2794 0.9906)
			(stroke
				(width 0.1)
				(type default)
			)
			(layer "B.Fab")
		)
		(fp_line
			(start -0.2794 0.9906)
			(end -0.2794 -0.1016)
			(stroke
				(width 0.1)
				(type default)
			)
			(layer "B.Fab")
		)
		(pad "1" smd rect
			(at 0 0 270)
			(size 0.508 0.508)
			(layers "B.Cu" "B.Mask" "B.Paste")
			(net "VR_PVCCIO_CPU0_AIREF1")
		)
		(pad "2" smd rect
			(at 0 0.889 270)
			(size 0.508 0.508)
			(layers "B.Cu" "B.Mask" "B.Paste")
			(net "ISENSE_PVCCIO_CPU0_PH1_IMON")
		)
		(zone
			(layer "B.Cu")
			(hatch none 0.5)
			(connect_pads
				(clearance 0)
			)
			(min_thickness 0.25)
			(keepout
				(tracks allowed)
				(vias not_allowed)
				(pads allowed)
				(copperpour not_allowed)
				(footprints allowed)
			)
			(placement
				(enabled no)
				(sheetname "")
			)
			(fill
				(thermal_gap 0.5)
				(thermal_bridge_width 0.5)
				(island_removal_mode 0)
			)
			(polygon
				(pts
					(xy 344.715846 -91.22537) (xy 344.715846 -90.71737) (xy 345.096846 -90.71737) (xy 345.096846 -91.22537)
				)
			)
		)
		(zone
			(layer "B.Cu")
			(hatch none 0.5)
			(connect_pads
				(clearance 0)
			)
			(min_thickness 0.25)
			(keepout
				(tracks not_allowed)
				(vias allowed)
				(pads allowed)
				(copperpour not_allowed)
				(footprints allowed)
			)
			(placement
				(enabled no)
				(sheetname "")
			)
			(fill
				(thermal_gap 0.5)
				(thermal_bridge_width 0.5)
				(island_removal_mode 0)
			)
			(polygon
				(pts
					(xy 345.096846 -91.22537) (xy 345.096846 -90.71737) (xy 344.715846 -90.71737) (xy 344.715846 -91.22537)
				)
			)
		)
	)
	(footprint ""
		(layer "B.Cu")
		(at 91.619324 -157.004258 90)
		(property "Reference" "C8L3"
			(at -1.47828 0.78994 180)
			(unlocked yes)
			(layer "B.SilkS")
			(effects
				(font
					(size 0.4064 0.254)
					(thickness 0.1524)
				)
				(justify mirror)
			)
		)
		(property "Value" ""
			(at 0 0 90)
			(layer "B.Fab")
			(effects
				(font
					(size 1.27 1.27)
				)
				(justify mirror)
			)
		)
		(duplicate_pad_numbers_are_jumpers no)
		(fp_poly
			(pts
				(xy 0.7239 -0.2159) (xy -0.7239 -0.2159) (xy -0.7239 1.9939) (xy 0.7239 1.9939)
			)
			(stroke
				(width 0)
				(type default)
			)
			(fill no)
			(layer "B.CrtYd")
		)
		(fp_line
			(start 0.7239 -0.2159)
			(end 0.7239 1.9939)
			(stroke
				(width 0.1)
				(type default)
			)
			(layer "B.Fab")
		)
		(fp_line
			(start -0.7239 -0.2159)
			(end 0.7239 -0.2159)
			(stroke
				(width 0.1)
				(type default)
			)
			(layer "B.Fab")
		)
		(fp_line
			(start 0.7239 1.9939)
			(end -0.7239 1.9939)
			(stroke
				(width 0.1)
				(type default)
			)
			(layer "B.Fab")
		)
		(fp_line
			(start -0.7239 1.9939)
			(end -0.7239 -0.2159)
			(stroke
				(width 0.1)
				(type default)
			)
			(layer "B.Fab")
		)
		(pad "1" smd rect
			(at 0 0 270)
			(size 1.27 1.016)
			(layers "B.Cu" "B.Mask" "B.Paste")
			(net "PVTT_KLM")
		)
		(pad "2" smd rect
			(at 0 1.778 270)
			(size 1.27 1.016)
			(layers "B.Cu" "B.Mask" "B.Paste")
			(net "GND")
		)
		(zone
			(layer "B.Cu")
			(hatch none 0.5)
			(connect_pads
				(clearance 0)
			)
			(min_thickness 0.25)
			(keepout
				(tracks not_allowed)
				(vias allowed)
				(pads allowed)
				(copperpour not_allowed)
				(footprints allowed)
			)
			(placement
				(enabled no)
				(sheetname "")
			)
			(fill
				(thermal_gap 0.5)
				(thermal_bridge_width 0.5)
				(island_removal_mode 0)
			)
			(polygon
				(pts
					(xy 92.127324 -157.639258) (xy 92.127324 -156.369258) (xy 92.889324 -156.369258) (xy 92.889324 -157.639258)
				)
			)
		)
	)
	(footprint ""
		(layer "B.Cu")
		(at 401.574 -87.3125 180)
		(property "Reference" "R2N26"
			(at 0.8382 -0.67818 180)
			(unlocked yes)
			(layer "B.SilkS")
			(effects
				(font
					(size 0.4064 0.254)
					(thickness 0.1524)
				)
				(justify left mirror)
			)
		)
		(property "Value" ""
			(at 0 0 0)
			(layer "B.Fab")
			(effects
				(font
					(size 1.27 1.27)
				)
				(justify mirror)
			)
		)
		(duplicate_pad_numbers_are_jumpers no)
		(fp_poly
			(pts
				(xy 0.2794 -0.1016) (xy -0.2794 -0.1016) (xy -0.2794 0.9906) (xy 0.2794 0.9906)
			)
			(stroke
				(width 0)
				(type default)
			)
			(fill no)
			(layer "B.CrtYd")
		)
		(fp_line
			(start 0.2794 0.9906)
			(end -0.2794 0.9906)
			(stroke
				(width 0.1)
				(type default)
			)
			(layer "B.Fab")
		)
		(fp_line
			(start 0.2794 -0.1016)
			(end 0.2794 0.9906)
			(stroke
				(width 0.1)
				(type default)
			)
			(layer "B.Fab")
		)
		(fp_line
			(start -0.2794 0.9906)
			(end -0.2794 -0.1016)
			(stroke
				(width 0.1)
				(type default)
			)
			(layer "B.Fab")
		)
		(fp_line
			(start -0.2794 -0.1016)
			(end 0.2794 -0.1016)
			(stroke
				(width 0.1)
				(type default)
			)
			(layer "B.Fab")
		)
		(pad "1" smd rect
			(at 0 0)
			(size 0.508 0.508)
			(layers "B.Cu" "B.Mask" "B.Paste")
			(net "FM_ADR_COMPLETE")
		)
		(pad "2" smd rect
			(at 0 0.889)
			(size 0.508 0.508)
			(layers "B.Cu" "B.Mask" "B.Paste")
			(net "FM_ADR_COMPLETE_R1")
		)
		(zone
			(layer "B.Cu")
			(hatch none 0.5)
			(connect_pads
				(clearance 0)
			)
			(min_thickness 0.25)
			(keepout
				(tracks not_allowed)
				(vias allowed)
				(pads allowed)
				(copperpour not_allowed)
				(footprints allowed)
			)
			(placement
				(enabled no)
				(sheetname "")
			)
			(fill
				(thermal_gap 0.5)
				(thermal_bridge_width 0.5)
				(island_removal_mode 0)
			)
			(polygon
				(pts
					(xy 401.32 -87.9475) (xy 401.828 -87.9475) (xy 401.828 -87.5665) (xy 401.32 -87.5665)
				)
			)
		)
		(zone
			(layer "B.Cu")
			(hatch none 0.5)
			(connect_pads
				(clearance 0)
			)
			(min_thickness 0.25)
			(keepout
				(tracks allowed)
				(vias not_allowed)
				(pads allowed)
				(copperpour not_allowed)
				(footprints allowed)
			)
			(placement
				(enabled no)
				(sheetname "")
			)
			(fill
				(thermal_gap 0.5)
				(thermal_bridge_width 0.5)
				(island_removal_mode 0)
			)
			(polygon
				(pts
					(xy 401.32 -87.5665) (xy 401.828 -87.5665) (xy 401.828 -87.9475) (xy 401.32 -87.9475)
				)
			)
		)
	)
)
